(kicad_pcb
	(version 20241229)
	(generator "pcbnew")
	(generator_version "9.0")
	(general
		(thickness 1.62)
		(legacy_teardrops no)
	)
	(paper "A3")
	(title_block
		(title "COM Express 7 Baseboard")
		(date "2025-02-04")
		(rev "1.1.2")
		(company "Antmicro Ltd")
		(comment 1 "www.antmicro.com")
		(comment 9 "footprints 459-462 of 802")
	)
	(layers
		(0 "F.Cu" signal)
		(4 "In1.Cu" signal)
		(6 "In2.Cu" signal)
		(8 "In3.Cu" signal)
		(10 "In4.Cu" signal)
		(12 "In5.Cu" signal)
		(14 "In6.Cu" signal)
		(2 "B.Cu" signal)
		(9 "F.Adhes" user "F.Adhesive")
		(11 "B.Adhes" user "B.Adhesive")
		(13 "F.Paste" user)
		(15 "B.Paste" user)
		(5 "F.SilkS" user "F.Silkscreen")
		(7 "B.SilkS" user "B.Silkscreen")
		(1 "F.Mask" user)
		(3 "B.Mask" user)
		(17 "Dwgs.User" user "User.Drawings")
		(19 "Cmts.User" user "User.Comments")
		(21 "Eco1.User" user "User.Eco1")
		(23 "Eco2.User" user "User.Eco2")
		(25 "Edge.Cuts" user)
		(27 "Margin" user)
		(31 "F.CrtYd" user "F.Courtyard")
		(29 "B.CrtYd" user "B.Courtyard")
		(35 "F.Fab" user)
		(33 "B.Fab" user)
	)
	(footprint "antmicro-footprints:TSSOP-8_3x3mm_P0.65mm"
		(layer "F.Cu")
		(at 262.430708 78.085)
		(property "Reference" "U27"
			(at -0.96 2.725 0)
			(layer "F.SilkS")
			(effects
				(font
					(size 0.7 0.7)
					(thickness 0.15)
				)
				(justify left bottom)
			)
		)
		(property "Value" "NTS0102_TSSOP"
			(at 0 2.8 0)
			(layer "F.Fab")
			(effects
				(font
					(size 0.7 0.7)
					(thickness 0.15)
				)
				(justify left bottom)
			)
		)
		(property "Datasheet" "https://www.mouser.com/datasheet/2/302/NTS0102-1127324.pdf"
			(at 0 0 0)
			(layer "F.Fab")
			(hide yes)
			(effects
				(font
					(size 1.27 1.27)
					(thickness 0.15)
				)
			)
		)
		(property "Author" "Antmicro"
			(at 0 0 0)
			(layer "F.Fab")
			(hide yes)
			(effects
				(font
					(size 1 1)
					(thickness 0.15)
				)
			)
		)
		(property "License" "Apache-2.0"
			(at 0 0 0)
			(layer "F.Fab")
			(hide yes)
			(effects
				(font
					(size 1 1)
					(thickness 0.15)
				)
			)
		)
		(property "MPN" "NTS0102DP"
			(at 0 0 0)
			(layer "F.Fab")
			(hide yes)
			(effects
				(font
					(size 1 1)
					(thickness 0.15)
				)
			)
		)
		(property "Manufacturer" "NXP"
			(at 0 0 0)
			(layer "F.Fab")
			(hide yes)
			(effects
				(font
					(size 1 1)
					(thickness 0.15)
				)
			)
		)
		(sheetname "Misc")
		(sheetfile "misc.kicad_sch")
		(attr smd)
		(fp_line
			(start -1.55 1.561)
			(end 1.552 1.561)
			(stroke
				(width 0.15)
				(type solid)
			)
			(layer "F.SilkS")
		)
		(fp_line
			(start -1.525 -1.537)
			(end 1.552 -1.539)
			(stroke
				(width 0.15)
				(type solid)
			)
			(layer "F.SilkS")
		)
		(fp_circle
			(center -1.87 -1.4)
			(end -1.82 -1.4)
			(stroke
				(width 0.15)
				(type solid)
			)
			(fill yes)
			(layer "F.SilkS")
		)
		(fp_rect
			(start -3.15 -1.789)
			(end 3.15 1.811)
			(stroke
				(width 0.05)
				(type solid)
			)
			(fill no)
			(layer "F.CrtYd")
		)
		(fp_line
			(start -1.55 -0.937)
			(end -1.55 1.561)
			(stroke
				(width 0.15)
				(type solid)
			)
			(layer "F.Fab")
		)
		(fp_line
			(start -1.55 -0.937)
			(end -0.949 -1.539)
			(stroke
				(width 0.15)
				(type solid)
			)
			(layer "F.Fab")
		)
		(fp_line
			(start -1.55 1.561)
			(end 1.552 1.561)
			(stroke
				(width 0.15)
				(type solid)
			)
			(layer "F.Fab")
		)
		(fp_line
			(start -0.949 -1.539)
			(end 1.552 -1.539)
			(stroke
				(width 0.15)
				(type solid)
			)
			(layer "F.Fab")
		)
		(fp_line
			(start 1.552 -1.539)
			(end 1.552 1.561)
			(stroke
				(width 0.15)
				(type solid)
			)
			(layer "F.Fab")
		)
		(pad "1" smd roundrect
			(at -2.148 -0.962)
			(size 1.47 0.4)
			(layers "F.Cu" "F.Mask" "F.Paste")
			(roundrect_rratio 0.25)
			(net 280 "/Misc/PWM_{A5V}")
			(pinfunction "B_{2}")
			(pintype "bidirectional")
			(teardrops
				(best_length_ratio 0.2)
				(max_length 1)
				(best_width_ratio 0.9)
				(max_width 2)
				(curved_edges yes)
				(filter_ratio 0.9)
				(enabled yes)
				(allow_two_segments yes)
				(prefer_zone_connections yes)
			)
		)
		(pad "2" smd roundrect
			(at -2.148 -0.313)
			(size 1.47 0.4)
			(layers "F.Cu" "F.Mask" "F.Paste")
			(roundrect_rratio 0.25)
			(net 1 "GND")
			(pinfunction "GND")
			(pintype "power_in")
			(teardrops
				(best_length_ratio 0.2)
				(max_length 1)
				(best_width_ratio 0.9)
				(max_width 2)
				(curved_edges yes)
				(filter_ratio 0.9)
				(enabled yes)
				(allow_two_segments yes)
				(prefer_zone_connections yes)
			)
		)
		(pad "3" smd roundrect
			(at -2.148 0.338)
			(size 1.47 0.4)
			(layers "F.Cu" "F.Mask" "F.Paste")
			(roundrect_rratio 0.25)
			(net 2 "+3V3")
			(pinfunction "VCC_{A}")
			(pintype "power_in")
			(teardrops
				(best_length_ratio 0.2)
				(max_length 1)
				(best_width_ratio 0.9)
				(max_width 2)
				(curved_edges yes)
				(filter_ratio 0.9)
				(enabled yes)
				(allow_two_segments yes)
				(prefer_zone_connections yes)
			)
		)
		(pad "4" smd roundrect
			(at -2.148 0.987)
			(size 1.47 0.4)
			(layers "F.Cu" "F.Mask" "F.Paste")
			(roundrect_rratio 0.25)
			(net 782 "/Misc/PWM_{A3V3}")
			(pinfunction "A_{2}")
			(pintype "bidirectional")
			(teardrops
				(best_length_ratio 0.2)
				(max_length 1)
				(best_width_ratio 0.9)
				(max_width 2)
				(curved_edges yes)
				(filter_ratio 0.9)
				(enabled yes)
				(allow_two_segments yes)
				(prefer_zone_connections yes)
			)
		)
		(pad "5" smd roundrect
			(at 2.151 0.987)
			(size 1.47 0.4)
			(layers "F.Cu" "F.Mask" "F.Paste")
			(roundrect_rratio 0.25)
			(net 780 "/Misc/TACH_{A3V3}")
			(pinfunction "A_{1}")
			(pintype "bidirectional")
			(teardrops
				(best_length_ratio 0.2)
				(max_length 1)
				(best_width_ratio 0.9)
				(max_width 2)
				(curved_edges yes)
				(filter_ratio 0.9)
				(enabled yes)
				(allow_two_segments yes)
				(prefer_zone_connections yes)
			)
		)
		(pad "6" smd roundrect
			(at 2.151 0.338)
			(size 1.47 0.4)
			(layers "F.Cu" "F.Mask" "F.Paste")
			(roundrect_rratio 0.25)
			(net 2 "+3V3")
			(pinfunction "OE")
			(pintype "input")
			(teardrops
				(best_length_ratio 0.2)
				(max_length 1)
				(best_width_ratio 0.9)
				(max_width 2)
				(curved_edges yes)
				(filter_ratio 0.9)
				(enabled yes)
				(allow_two_segments yes)
				(prefer_zone_connections yes)
			)
		)
		(pad "7" smd roundrect
			(at 2.151 -0.313)
			(size 1.47 0.4)
			(layers "F.Cu" "F.Mask" "F.Paste")
			(roundrect_rratio 0.25)
			(net 52 "+5V")
			(pinfunction "VCC_{B}")
			(pintype "power_in")
			(teardrops
				(best_length_ratio 0.2)
				(max_length 1)
				(best_width_ratio 0.9)
				(max_width 2)
				(curved_edges yes)
				(filter_ratio 0.9)
				(enabled yes)
				(allow_two_segments yes)
				(prefer_zone_connections yes)
			)
		)
		(pad "8" smd roundrect
			(at 2.151 -0.962)
			(size 1.47 0.4)
			(layers "F.Cu" "F.Mask" "F.Paste")
			(roundrect_rratio 0.25)
			(net 279 "/Misc/TACH_{A5V}")
			(pinfunction "B_{1}")
			(pintype "bidirectional")
			(teardrops
				(best_length_ratio 0.2)
				(max_length 1)
				(best_width_ratio 0.9)
				(max_width 2)
				(curved_edges yes)
				(filter_ratio 0.9)
				(enabled yes)
				(allow_two_segments yes)
				(prefer_zone_connections yes)
			)
		)
	)
	(footprint "antmicro-footprints:R_0402_1005Metric"
		(layer "F.Cu")
		(at 237.77 151.931001)
		(descr "Resistor SMD 0402")
		(tags "resistor SMD 0402")
		(property "Reference" "R171"
			(at 0.83 0.428999 0)
			(layer "F.SilkS")
			(effects
				(font
					(size 0.7 0.7)
					(thickness 0.15)
				)
				(justify left bottom)
			)
		)
		(property "Value" "R_1k_0402"
			(at -1.011843 1.772047 0)
			(layer "F.Fab")
			(effects
				(font
					(size 0.7 0.7)
					(thickness 0.15)
				)
				(justify left bottom)
			)
		)
		(property "Datasheet" "https://www.bourns.com/docs/product-datasheets/cr.pdf"
			(at 0 0 0)
			(layer "F.Fab")
			(hide yes)
			(effects
				(font
					(size 1.27 1.27)
					(thickness 0.15)
				)
			)
		)
		(property "Author" "Antmicro"
			(at 0 0 0)
			(layer "F.Fab")
			(hide yes)
			(effects
				(font
					(size 1 1)
					(thickness 0.15)
				)
			)
		)
		(property "License" "Apache-2.0"
			(at 0 0 0)
			(layer "F.Fab")
			(hide yes)
			(effects
				(font
					(size 1 1)
					(thickness 0.15)
				)
			)
		)
		(property "MPN" "CR0402-FX-1001GLF"
			(at 0 0 0)
			(layer "F.Fab")
			(hide yes)
			(effects
				(font
					(size 1 1)
					(thickness 0.15)
				)
			)
		)
		(property "Manufacturer" "Bourns"
			(at 0 0 0)
			(layer "F.Fab")
			(hide yes)
			(effects
				(font
					(size 1 1)
					(thickness 0.15)
				)
			)
		)
		(property "Public" "False"
			(at 0 0 0)
			(layer "F.Fab")
			(hide yes)
			(effects
				(font
					(size 1 1)
					(thickness 0.15)
				)
			)
		)
		(property "Tolerance" "1%"
			(at 0 0 0)
			(layer "F.Fab")
			(hide yes)
			(effects
				(font
					(size 1 1)
					(thickness 0.15)
				)
			)
		)
		(property "Val" "1k"
			(at 0 0 0)
			(layer "F.Fab")
			(hide yes)
			(effects
				(font
					(size 1 1)
					(thickness 0.15)
				)
			)
		)
		(sheetname "Com Express 7 MGMT")
		(sheetfile "com_express_7_mgmt.kicad_sch")
		(attr smd)
		(fp_rect
			(start -0.925 -0.47)
			(end 0.925 0.47)
			(stroke
				(width 0.05)
				(type default)
			)
			(fill no)
			(layer "F.CrtYd")
		)
		(fp_rect
			(start -0.5 -0.25)
			(end 0.5 0.25)
			(stroke
				(width 0.15)
				(type solid)
			)
			(fill no)
			(layer "F.Fab")
		)
		(pad "1" smd roundrect
			(at -0.48 0)
			(size 0.59 0.64)
			(layers "F.Cu" "F.Mask" "F.Paste")
			(roundrect_rratio 0.25)
			(net 1 "GND")
			(pintype "passive")
			(teardrops
				(best_length_ratio 0.2)
				(max_length 1)
				(best_width_ratio 0.9)
				(max_width 2)
				(curved_edges yes)
				(filter_ratio 0.9)
				(enabled yes)
				(allow_two_segments yes)
				(prefer_zone_connections yes)
			)
		)
		(pad "2" smd roundrect
			(at 0.48 0)
			(size 0.59 0.64)
			(layers "F.Cu" "F.Mask" "F.Paste")
			(roundrect_rratio 0.25)
			(net 598 "Net-(U31-~{WC})")
			(pintype "passive")
			(teardrops
				(best_length_ratio 0.2)
				(max_length 1)
				(best_width_ratio 0.9)
				(max_width 2)
				(curved_edges yes)
				(filter_ratio 0.9)
				(enabled yes)
				(allow_two_segments yes)
				(prefer_zone_connections yes)
			)
		)
	)
	(footprint "antmicro-footprints:R_0402_1005Metric"
		(layer "F.Cu")
		(at 155.299 159.11 180)
		(descr "Resistor SMD 0402")
		(tags "resistor SMD 0402")
		(property "Reference" "R44"
			(at -6.701 17.5 0)
			(layer "F.SilkS")
			(effects
				(font
					(size 0.7 0.7)
					(thickness 0.15)
				)
				(justify right bottom)
			)
		)
		(property "Value" "R_0R_0402"
			(at -1.011843 1.772047 0)
			(layer "F.Fab")
			(effects
				(font
					(size 0.7 0.7)
					(thickness 0.15)
				)
				(justify right bottom)
			)
		)
		(property "Datasheet" "https://industrial.panasonic.com/cdbs/www-data/pdf/RDA0000/AOA0000C301.pdf"
			(at 0 0 180)
			(layer "F.Fab")
			(hide yes)
			(effects
				(font
					(size 1.27 1.27)
					(thickness 0.15)
				)
			)
		)
		(property "Author" "Antmicro"
			(at 310.598 318.22 0)
			(layer "F.Fab")
			(hide yes)
			(effects
				(font
					(size 1 1)
					(thickness 0.15)
				)
			)
		)
		(property "Current" "1A"
			(at 310.598 318.22 0)
			(layer "F.Fab")
			(hide yes)
			(effects
				(font
					(size 1 1)
					(thickness 0.15)
				)
			)
		)
		(property "License" "Apache-2.0"
			(at 310.598 318.22 0)
			(layer "F.Fab")
			(hide yes)
			(effects
				(font
					(size 1 1)
					(thickness 0.15)
				)
			)
		)
		(property "MPN" "ERJ2GE0R00X"
			(at 310.598 318.22 0)
			(layer "F.Fab")
			(hide yes)
			(effects
				(font
					(size 1 1)
					(thickness 0.15)
				)
			)
		)
		(property "Manufacturer" "Panasonic"
			(at 310.598 318.22 0)
			(layer "F.Fab")
			(hide yes)
			(effects
				(font
					(size 1 1)
					(thickness 0.15)
				)
			)
		)
		(property "Public" "False"
			(at 310.598 318.22 0)
			(layer "F.Fab")
			(hide yes)
			(effects
				(font
					(size 1 1)
					(thickness 0.15)
				)
			)
		)
		(property "Tolerance" ""
			(at 310.598 318.22 0)
			(layer "F.Fab")
			(hide yes)
			(effects
				(font
					(size 1 1)
					(thickness 0.15)
				)
			)
		)
		(property "Val" "0R"
			(at 310.598 318.22 0)
			(layer "F.Fab")
			(hide yes)
			(effects
				(font
					(size 1 1)
					(thickness 0.15)
				)
			)
		)
		(sheetname "2xSFP+")
		(sheetfile "2xSFP+.kicad_sch")
		(attr smd)
		(fp_rect
			(start -0.925 -0.47)
			(end 0.925 0.47)
			(stroke
				(width 0.05)
				(type default)
			)
			(fill no)
			(layer "F.CrtYd")
		)
		(fp_rect
			(start -0.5 -0.25)
			(end 0.5 0.25)
			(stroke
				(width 0.15)
				(type solid)
			)
			(fill no)
			(layer "F.Fab")
		)
		(pad "1" smd roundrect
			(at -0.48 0 180)
			(size 0.59 0.64)
			(layers "F.Cu" "F.Mask" "F.Paste")
			(roundrect_rratio 0.25)
			(net 563 "/2xSFP+/~{LED0_1}")
			(pintype "passive")
			(teardrops
				(best_length_ratio 0.2)
				(max_length 1)
				(best_width_ratio 0.9)
				(max_width 2)
				(curved_edges yes)
				(filter_ratio 0.9)
				(enabled yes)
				(allow_two_segments yes)
				(prefer_zone_connections yes)
			)
		)
		(pad "2" smd roundrect
			(at 0.48 0 180)
			(size 0.59 0.64)
			(layers "F.Cu" "F.Mask" "F.Paste")
			(roundrect_rratio 0.25)
			(net 931 "/2xSFP+/SFP0_LEDG")
			(pintype "passive")
			(teardrops
				(best_length_ratio 0.2)
				(max_length 1)
				(best_width_ratio 0.9)
				(max_width 2)
				(curved_edges yes)
				(filter_ratio 0.9)
				(enabled yes)
				(allow_two_segments yes)
				(prefer_zone_connections yes)
			)
		)
	)
	(footprint "antmicro-footprints:C_0402_1005Metric"
		(layer "F.Cu")
		(at 114.4 146.301 90)
		(descr "Capacitor SMD 0402")
		(tags "capacitor SMD 0402")
		(property "Reference" "C112"
			(at 10.541 2.6 90)
			(layer "F.SilkS")
			(effects
				(font
					(size 0.7 0.7)
					(thickness 0.15)
				)
				(justify left bottom)
			)
		)
		(property "Value" "C_100n_0402"
			(at -1.022927 2.155213 90)
			(layer "F.Fab")
			(effects
				(font
					(size 0.7 0.7)
					(thickness 0.15)
				)
				(justify left bottom)
			)
		)
		(property "Datasheet" "https://www.murata.com/products/productdetail?partno=GRM155R61H104KE14%23"
			(at 0 0 90)
			(layer "F.Fab")
			(hide yes)
			(effects
				(font
					(size 1.27 1.27)
					(thickness 0.15)
				)
			)
		)
		(property "Author" "Antmicro"
			(at 260.701 31.901 0)
			(layer "F.Fab")
			(hide yes)
			(effects
				(font
					(size 1 1)
					(thickness 0.15)
				)
			)
		)
		(property "Dielectric" "X5R"
			(at 260.701 31.901 0)
			(layer "F.Fab")
			(hide yes)
			(effects
				(font
					(size 1 1)
					(thickness 0.15)
				)
			)
		)
		(property "License" "Apache-2.0"
			(at 260.701 31.901 0)
			(layer "F.Fab")
			(hide yes)
			(effects
				(font
					(size 1 1)
					(thickness 0.15)
				)
			)
		)
		(property "MPN" "GRM155R61H104KE14D"
			(at 260.701 31.901 0)
			(layer "F.Fab")
			(hide yes)
			(effects
				(font
					(size 1 1)
					(thickness 0.15)
				)
			)
		)
		(property "Manufacturer" "Murata"
			(at 260.701 31.901 0)
			(layer "F.Fab")
			(hide yes)
			(effects
				(font
					(size 1 1)
					(thickness 0.15)
				)
			)
		)
		(property "Public" "False"
			(at 260.701 31.901 0)
			(layer "F.Fab")
			(hide yes)
			(effects
				(font
					(size 1 1)
					(thickness 0.15)
				)
			)
		)
		(property "Val" "100n"
			(at 260.701 31.901 0)
			(layer "F.Fab")
			(hide yes)
			(effects
				(font
					(size 1 1)
					(thickness 0.15)
				)
			)
		)
		(property "Voltage" "50V"
			(at 260.701 31.901 0)
			(layer "F.Fab")
			(hide yes)
			(effects
				(font
					(size 1 1)
					(thickness 0.15)
				)
			)
		)
		(sheetname "PCIe redriver")
		(sheetfile "pcie_redriver.kicad_sch")
		(attr smd)
		(fp_rect
			(start -0.925 -0.47)
			(end 0.925 0.47)
			(stroke
				(width 0.05)
				(type default)
			)
			(fill no)
			(layer "F.CrtYd")
		)
		(fp_line
			(start 0.504 -0.25)
			(end 0.504 0.248)
			(stroke
				(width 0.15)
				(type solid)
			)
			(layer "F.Fab")
		)
		(fp_line
			(start -0.494 -0.25)
			(end 0.504 -0.25)
			(stroke
				(width 0.15)
				(type solid)
			)
			(layer "F.Fab")
		)
		(fp_line
			(start 0.504 0.248)
			(end -0.494 0.248)
			(stroke
				(width 0.15)
				(type solid)
			)
			(layer "F.Fab")
		)
		(fp_line
			(start -0.494 0.248)
			(end -0.494 -0.25)
			(stroke
				(width 0.15)
				(type solid)
			)
			(layer "F.Fab")
		)
		(pad "1" smd roundrect
			(at -0.48 0 90)
			(size 0.59 0.64)
			(layers "F.Cu" "F.Mask" "F.Paste")
			(roundrect_rratio 0.25)
			(net 1 "GND")
			(pintype "passive")
			(teardrops
				(best_length_ratio 0.2)
				(max_length 1)
				(best_width_ratio 0.9)
				(max_width 2)
				(curved_edges yes)
				(filter_ratio 0.9)
				(enabled yes)
				(allow_two_segments yes)
				(prefer_zone_connections yes)
			)
		)
		(pad "2" smd roundrect
			(at 0.48 0 90)
			(size 0.59 0.64)
			(layers "F.Cu" "F.Mask" "F.Paste")
			(roundrect_rratio 0.25)
			(net 2 "+3V3")
			(pintype "passive")
			(teardrops
				(best_length_ratio 0.2)
				(max_length 1)
				(best_width_ratio 0.9)
				(max_width 2)
				(curved_edges yes)
				(filter_ratio 0.9)
				(enabled yes)
				(allow_two_segments yes)
				(prefer_zone_connections yes)
			)
		)
	)
)
